(kicad_pcb
	(version 20240108)
	(generator "pcbnew")
	(generator_version "8.0")
	(general
		(thickness 1.62)
		(legacy_teardrops no)
	)
	(paper "A4")
	(title_block
		(title "Jetson Orin Baseboard")
		(date "2025-03-12")
		(rev "1.3.4")
		(company "Antmicro Ltd")
		(comment 1 "www.antmicro.com")
		(comment 9 "footprints 177-181 of 677")
	)
	(layers
		(0 "F.Cu" signal)
		(1 "In1.Cu" signal)
		(2 "In2.Cu" signal)
		(3 "In3.Cu" signal)
		(4 "In4.Cu" jumper)
		(5 "In5.Cu" signal)
		(6 "In6.Cu" signal)
		(31 "B.Cu" signal)
		(32 "B.Adhes" user "B.Adhesive")
		(33 "F.Adhes" user "F.Adhesive")
		(34 "B.Paste" user)
		(35 "F.Paste" user)
		(36 "B.SilkS" user "B.Silkscreen")
		(37 "F.SilkS" user "F.Silkscreen")
		(38 "B.Mask" user)
		(39 "F.Mask" user)
		(40 "Dwgs.User" user "User.Drawings")
		(41 "Cmts.User" user "User.Comments")
		(42 "Eco1.User" user "User.Eco1")
		(43 "Eco2.User" user "User.Eco2")
		(44 "Edge.Cuts" user)
		(45 "Margin" user)
		(46 "B.CrtYd" user "B.Courtyard")
		(47 "F.CrtYd" user "F.Courtyard")
		(48 "B.Fab" user)
		(49 "F.Fab" user)
	)
	(footprint "antmicro-footprints:USON-8_2x3mm_P0.5mm"
		(layer "F.Cu")
		(at 82.02 115.4 -90)
		(property "Reference" "U7"
			(at -1.79 -1.89 90)
			(layer "F.SilkS")
			(effects
				(font
					(size 0.7 0.7)
					(thickness 0.15)
				)
				(justify left bottom)
			)
		)
		(property "Value" "W25Q80DV_USON"
			(at 0 2.3 -90)
			(layer "F.Fab")
			(effects
				(font
					(size 0.7 0.7)
					(thickness 0.15)
				)
				(justify left bottom)
			)
		)
		(property "Footprint" "antmicro-footprints:USON-8_2x3mm_P0.5mm"
			(at 0 0 -90)
			(layer "F.Fab")
			(hide yes)
			(effects
				(font
					(size 1.27 1.27)
					(thickness 0.15)
				)
			)
		)
		(property "Datasheet" "https://www.mouser.com/datasheet/2/949/w25q80dv_dl_revh_10022015-1489677.pdf"
			(at 0 0 -90)
			(layer "F.Fab")
			(hide yes)
			(effects
				(font
					(size 1.27 1.27)
					(thickness 0.15)
				)
			)
		)
		(property "Author" "Antmicro"
			(at -33.38 197.42 0)
			(layer "F.Fab")
			(hide yes)
			(effects
				(font
					(size 1 1)
					(thickness 0.15)
				)
			)
		)
		(property "License" "Apache-2.0"
			(at -33.38 197.42 0)
			(layer "F.Fab")
			(hide yes)
			(effects
				(font
					(size 1 1)
					(thickness 0.15)
				)
			)
		)
		(property "MPN" "W25Q80DVUXIE TR"
			(at -33.38 197.42 0)
			(layer "F.Fab")
			(hide yes)
			(effects
				(font
					(size 1 1)
					(thickness 0.15)
				)
			)
		)
		(property "Manufacturer" "Winbond"
			(at -33.38 197.42 0)
			(layer "F.Fab")
			(hide yes)
			(effects
				(font
					(size 1 1)
					(thickness 0.15)
				)
			)
		)
		(sheetname "USB Debug, DP")
		(sheetfile "usb.kicad_sch")
		(attr smd)
		(fp_line
			(start 1.71 1.3005)
			(end -1.71 1.3)
			(stroke
				(width 0.15)
				(type solid)
			)
			(layer "F.SilkS")
		)
		(fp_line
			(start -1.71 1.3)
			(end -1.71 -0.89)
			(stroke
				(width 0.15)
				(type solid)
			)
			(layer "F.SilkS")
		)
		(fp_line
			(start -1.71 -0.89)
			(end -1.3 -1.301)
			(stroke
				(width 0.15)
				(type solid)
			)
			(layer "F.SilkS")
		)
		(fp_line
			(start 1.71 -1.3005)
			(end 1.71 1.3005)
			(stroke
				(width 0.15)
				(type solid)
			)
			(layer "F.SilkS")
		)
		(fp_line
			(start -1.3 -1.301)
			(end 1.71 -1.3005)
			(stroke
				(width 0.15)
				(type solid)
			)
			(layer "F.SilkS")
		)
		(fp_circle
			(center -1.75 -1.25)
			(end -1.7 -1.25)
			(stroke
				(width 0.15)
				(type solid)
			)
			(fill solid)
			(layer "F.SilkS")
		)
		(fp_rect
			(start 1.9 -1.4)
			(end -1.9 1.4)
			(stroke
				(width 0.05)
				(type solid)
			)
			(fill none)
			(layer "F.CrtYd")
		)
		(fp_line
			(start -1.499 -0.5)
			(end -0.998 -1)
			(stroke
				(width 0.15)
				(type solid)
			)
			(layer "F.Fab")
		)
		(fp_rect
			(start 1.5 1)
			(end -1.5 -1)
			(stroke
				(width 0.15)
				(type solid)
			)
			(fill none)
			(layer "F.Fab")
		)
		(fp_text user "License: Apache-2.0"
			(at -1.9 7.099 -90)
			(layer "F.Fab")
			(hide yes)
			(effects
				(font
					(size 0.7 0.7)
					(thickness 0.15)
				)
				(justify left bottom)
			)
		)
		(fp_text user "Author: Antmicro"
			(at -1.9 6.099 -90)
			(layer "F.Fab")
			(hide yes)
			(effects
				(font
					(size 0.7 0.7)
					(thickness 0.15)
				)
				(justify left bottom)
			)
		)
		(fp_text user "${REFERENCE}"
			(at -1.9 5.099 -90)
			(layer "F.Fab")
			(hide yes)
			(effects
				(font
					(size 0.7 0.7)
					(thickness 0.15)
				)
				(justify left bottom)
			)
		)
		(pad "1" smd roundrect
			(at -1.273 -0.75 180)
			(size 0.3 0.7)
			(layers "F.Cu" "F.Paste" "F.Mask")
			(roundrect_rratio 0.25)
			(net 253 "~{PDC_CS}")
			(pinfunction "~{CS}")
			(pintype "input")
		)
		(pad "2" smd roundrect
			(at -1.273 -0.25 180)
			(size 0.3 0.7)
			(layers "F.Cu" "F.Paste" "F.Mask")
			(roundrect_rratio 0.25)
			(net 255 "PDC_MISO")
			(pinfunction "SO/IO1")
			(pintype "input")
		)
		(pad "3" smd roundrect
			(at -1.273 0.248 180)
			(size 0.3 0.7)
			(layers "F.Cu" "F.Paste" "F.Mask")
			(roundrect_rratio 0.25)
			(net 98 "EEPROM_PWR")
			(pinfunction "~{WP}/IO2")
			(pintype "input")
		)
		(pad "4" smd roundrect
			(at -1.273 0.748 180)
			(size 0.3 0.7)
			(layers "F.Cu" "F.Paste" "F.Mask")
			(roundrect_rratio 0.25)
			(net 1 "GND")
			(pinfunction "VSS")
			(pintype "power_in")
		)
		(pad "5" smd roundrect
			(at 1.276 0.748 180)
			(size 0.3 0.7)
			(layers "F.Cu" "F.Paste" "F.Mask")
			(roundrect_rratio 0.25)
			(net 256 "PDC_MOSI")
			(pinfunction "SI/IO0")
			(pintype "input")
		)
		(pad "6" smd roundrect
			(at 1.276 0.248 180)
			(size 0.3 0.7)
			(layers "F.Cu" "F.Paste" "F.Mask")
			(roundrect_rratio 0.25)
			(net 254 "PDC_SCLK")
			(pinfunction "SCLK")
			(pintype "input")
		)
		(pad "7" smd roundrect
			(at 1.276 -0.25 180)
			(size 0.3 0.7)
			(layers "F.Cu" "F.Paste" "F.Mask")
			(roundrect_rratio 0.25)
			(net 98 "EEPROM_PWR")
			(pinfunction "~{HOLD}/IO3")
			(pintype "input")
		)
		(pad "8" smd roundrect
			(at 1.276 -0.75 180)
			(size 0.3 0.7)
			(layers "F.Cu" "F.Paste" "F.Mask")
			(roundrect_rratio 0.25)
			(net 98 "EEPROM_PWR")
			(pinfunction "VCC")
			(pintype "power_in")
		)
		(pad "EP" smd roundrect
			(at 0 0 270)
			(size 0.2 1.6)
			(layers "F.Cu" "F.Paste" "F.Mask")
			(roundrect_rratio 0.25)
			(net 728 "unconnected-(U7-PadEP)")
			(pinfunction "EP")
			(pintype "power_in+no_connect")
		)
	)
	(footprint "antmicro-footprints:TP_SMD_0.75mm"
		(layer "F.Cu")
		(at 64.475 122.485 180)
		(property "Reference" "TP27"
			(at -0.45 0.42 -90)
			(layer "F.SilkS")
			(effects
				(font
					(size 0.7 0.7)
					(thickness 0.15)
				)
				(justify left bottom)
			)
		)
		(property "Value" "TP_0.75mm_SMD"
			(at 0 1.2 180)
			(layer "F.Fab")
			(effects
				(font
					(size 0.7 0.7)
					(thickness 0.15)
				)
				(justify left bottom)
			)
		)
		(property "Footprint" "antmicro-footprints:TP_SMD_0.75mm"
			(at 0 0 180)
			(layer "F.Fab")
			(hide yes)
			(effects
				(font
					(size 1.27 1.27)
					(thickness 0.15)
				)
			)
		)
		(property "Author" "Antmicro"
			(at 128.95 244.97 0)
			(layer "F.Fab")
			(hide yes)
			(effects
				(font
					(size 1 1)
					(thickness 0.15)
				)
			)
		)
		(property "License" "Apache-2.0"
			(at 128.95 244.97 0)
			(layer "F.Fab")
			(hide yes)
			(effects
				(font
					(size 1 1)
					(thickness 0.15)
				)
			)
		)
		(property "MPN" ""
			(at 128.95 244.97 0)
			(layer "F.Fab")
			(hide yes)
			(effects
				(font
					(size 1 1)
					(thickness 0.15)
				)
			)
		)
		(property "Manufacturer" ""
			(at 128.95 244.97 0)
			(layer "F.Fab")
			(hide yes)
			(effects
				(font
					(size 1 1)
					(thickness 0.15)
				)
			)
		)
		(sheetname "USB Debug, DP")
		(sheetfile "usb.kicad_sch")
		(attr exclude_from_pos_files exclude_from_bom)
		(fp_circle
			(center 0 0)
			(end 0.475 0)
			(stroke
				(width 0.05)
				(type default)
			)
			(fill none)
			(layer "F.CrtYd")
		)
		(fp_text user "Author: Antmicro"
			(at -0.4 3.901 180)
			(layer "F.Fab")
			(hide yes)
			(effects
				(font
					(size 0.7 0.7)
					(thickness 0.15)
				)
				(justify left bottom)
			)
		)
		(fp_text user "${REFERENCE}"
			(at -0.4 2.7 180)
			(layer "F.Fab")
			(hide yes)
			(effects
				(font
					(size 0.7 0.7)
					(thickness 0.15)
				)
				(justify left bottom)
			)
		)
		(fp_text user "License: Apache-2.0"
			(at -0.4 5.101 180)
			(layer "F.Fab")
			(hide yes)
			(effects
				(font
					(size 0.7 0.7)
					(thickness 0.15)
				)
				(justify left bottom)
			)
		)
		(pad "1" smd circle
			(at 0 0 180)
			(size 0.75 0.75)
			(layers "F.Cu" "F.Mask")
			(net 501 "/USB Debug, DP/USBC3_FLG")
			(pinfunction "1")
			(pintype "passive")
		)
	)
	(footprint "antmicro-footprints:LED_0603_1608Metric_G"
		(layer "F.Cu")
		(at 47 105.025 -90)
		(descr "LED SMD 0603 Green")
		(tags "LED SMD 0603 Green")
		(property "Reference" "D62"
			(at 11.075 -1.4 -90)
			(layer "F.SilkS")
			(effects
				(font
					(size 0.7 0.7)
					(thickness 0.15)
				)
				(justify right top)
			)
		)
		(property "Value" "LED_G_0603_LTST-C190GKT"
			(at -0.001 1.599 90)
			(layer "F.Fab")
			(effects
				(font
					(size 0.7 0.7)
					(thickness 0.15)
				)
				(justify right top)
			)
		)
		(property "Footprint" "antmicro-footprints:LED_0603_1608Metric_G"
			(at 0 0 90)
			(layer "F.Fab")
			(hide yes)
			(effects
				(font
					(size 1.27 1.27)
					(thickness 0.15)
				)
			)
		)
		(property "Datasheet" "https://media.digikey.com/pdf/Data%20Sheets/Lite-On%20PDFs/LTST-C190GKT.pdf"
			(at 0 0 90)
			(layer "F.Fab")
			(hide yes)
			(effects
				(font
					(size 1.27 1.27)
					(thickness 0.15)
				)
			)
		)
		(property "MPN" "LTST-C190GKT"
			(at 0 0 -90)
			(unlocked yes)
			(layer "F.Fab")
			(hide yes)
			(effects
				(font
					(size 1 1)
					(thickness 0.15)
				)
			)
		)
		(property "Manufacturer" "Lite-On"
			(at 0 0 -90)
			(unlocked yes)
			(layer "F.Fab")
			(hide yes)
			(effects
				(font
					(size 1 1)
					(thickness 0.15)
				)
			)
		)
		(property "Author" "Antmicro"
			(at 0 0 -90)
			(unlocked yes)
			(layer "F.Fab")
			(hide yes)
			(effects
				(font
					(size 1 1)
					(thickness 0.15)
				)
			)
		)
		(property "License" "Apache-2.0"
			(at 0 0 -90)
			(unlocked yes)
			(layer "F.Fab")
			(hide yes)
			(effects
				(font
					(size 1 1)
					(thickness 0.15)
				)
			)
		)
		(property "Color" "Green"
			(at 0 0 -90)
			(unlocked yes)
			(layer "F.Fab")
			(hide yes)
			(effects
				(font
					(size 1 1)
					(thickness 0.15)
				)
			)
		)
		(sheetname "Supply")
		(sheetfile "supply.kicad_sch")
		(attr smd)
		(fp_line
			(start 0.22 0.35)
			(end -0.22 0.35)
			(stroke
				(width 0.15)
				(type solid)
			)
			(layer "F.SilkS")
		)
		(fp_line
			(start -0.094672 0.201008)
			(end -0.094672 -0.198992)
			(stroke
				(width 0.1)
				(type solid)
			)
			(layer "F.SilkS")
		)
		(fp_line
			(start 0.105328 0.201008)
			(end -0.094672 0.001008)
			(stroke
				(width 0.1)
				(type solid)
			)
			(layer "F.SilkS")
		)
		(fp_line
			(start 0.105328 0.201008)
			(end 0.105328 -0.198992)
			(stroke
				(width 0.1)
				(type solid)
			)
			(layer "F.SilkS")
		)
		(fp_line
			(start -0.094672 0.001008)
			(end -0.24 0.001008)
			(stroke
				(width 0.1)
				(type solid)
			)
			(layer "F.SilkS")
		)
		(fp_line
			(start -0.094672 0.001008)
			(end 0.105328 -0.198992)
			(stroke
				(width 0.1)
				(type solid)
			)
			(layer "F.SilkS")
		)
		(fp_line
			(start 0.105328 0.001008)
			(end 0.24 0.001)
			(stroke
				(width 0.1)
				(type solid)
			)
			(layer "F.SilkS")
		)
		(fp_line
			(start -1.18 -0.319)
			(end -1.18 0.321)
			(stroke
				(width 0.15)
				(type solid)
			)
			(layer "F.SilkS")
		)
		(fp_line
			(start 0.22 -0.35)
			(end -0.22 -0.35)
			(stroke
				(width 0.15)
				(type solid)
			)
			(layer "F.SilkS")
		)
		(fp_rect
			(start 1.25 0.65)
			(end -1.25 -0.65)
			(stroke
				(width 0.05)
				(type solid)
			)
			(fill none)
			(layer "F.CrtYd")
		)
		(fp_line
			(start -0.199 0.2)
			(end -0.199 0.1)
			(stroke
				(width 0.15)
				(type solid)
			)
			(layer "F.Fab")
		)
		(fp_line
			(start 0.201 0.2)
			(end 0.201 0)
			(stroke
				(width 0.15)
				(type solid)
			)
			(layer "F.Fab")
		)
		(fp_line
			(start -0.199 0)
			(end -0.597 0)
			(stroke
				(width 0.15)
				(type solid)
			)
			(layer "F.Fab")
		)
		(fp_line
			(start -0.101 0)
			(end 0.201 0.2)
			(stroke
				(width 0.15)
				(type solid)
			)
			(layer "F.Fab")
		)
		(fp_line
			(start 0.201 0)
			(end 0.201 -0.202)
			(stroke
				(width 0.15)
				(type solid)
			)
			(layer "F.Fab")
		)
		(fp_line
			(start 0.599 0)
			(end 0.201 0)
			(stroke
				(width 0.15)
				(type solid)
			)
			(layer "F.Fab")
		)
		(fp_line
			(start -0.199 -0.202)
			(end -0.199 0.1)
			(stroke
				(width 0.15)
				(type solid)
			)
			(layer "F.Fab")
		)
		(fp_line
			(start 0.201 -0.202)
			(end -0.101 0)
			(stroke
				(width 0.15)
				(type solid)
			)
			(layer "F.Fab")
		)
		(fp_rect
			(start 0.848 0.4)
			(end -0.85 -0.402)
			(stroke
				(width 0.15)
				(type solid)
			)
			(fill none)
			(layer "F.Fab")
		)
		(fp_text user "License: Apache-2.0"
			(at -1.4224 3.599 90)
			(layer "F.Fab")
			(hide yes)
			(effects
				(font
					(size 0.7 0.7)
					(thickness 0.15)
				)
				(justify right top)
			)
		)
		(fp_text user "Author: Antmicro"
			(at -1.4224 4.799 90)
			(layer "F.Fab")
			(hide yes)
			(effects
				(font
					(size 0.7 0.7)
					(thickness 0.15)
				)
				(justify right top)
			)
		)
		(fp_text user "${REFERENCE}"
			(at -1.4224 5.999 90)
			(layer "F.Fab")
			(hide yes)
			(effects
				(font
					(size 0.7 0.7)
					(thickness 0.15)
				)
				(justify right top)
			)
		)
		(pad "1" smd roundrect
			(at -0.7 0 90)
			(size 0.8 1)
			(layers "F.Cu" "F.Paste" "F.Mask")
			(roundrect_rratio 0.2)
			(net 793 "Net-(D62-C)")
			(pinfunction "C")
			(pintype "passive")
		)
		(pad "2" smd roundrect
			(at 0.7 0 90)
			(size 0.8 1)
			(layers "F.Cu" "F.Paste" "F.Mask")
			(roundrect_rratio 0.2)
			(net 798 "Net-(D62-A)")
			(pinfunction "A")
			(pintype "passive")
		)
	)
	(footprint "antmicro-footprints:TP_SMD_0.75mm"
		(layer "F.Cu")
		(at 127.905 115.235 180)
		(property "Reference" "TP6"
			(at -0.46 -0.445 0)
			(layer "F.SilkS")
			(effects
				(font
					(size 0.7 0.7)
					(thickness 0.15)
				)
				(justify left bottom)
			)
		)
		(property "Value" "TP_0.75mm_SMD"
			(at 0 1.2 180)
			(layer "F.Fab")
			(effects
				(font
					(size 0.7 0.7)
					(thickness 0.15)
				)
				(justify left bottom)
			)
		)
		(property "Footprint" "antmicro-footprints:TP_SMD_0.75mm"
			(at 0 0 180)
			(layer "F.Fab")
			(hide yes)
			(effects
				(font
					(size 1.27 1.27)
					(thickness 0.15)
				)
			)
		)
		(property "Author" "Antmicro"
			(at 255.81 230.47 0)
			(layer "F.Fab")
			(hide yes)
			(effects
				(font
					(size 1 1)
					(thickness 0.15)
				)
			)
		)
		(property "License" "Apache-2.0"
			(at 255.81 230.47 0)
			(layer "F.Fab")
			(hide yes)
			(effects
				(font
					(size 1 1)
					(thickness 0.15)
				)
			)
		)
		(property "MPN" ""
			(at 255.81 230.47 0)
			(layer "F.Fab")
			(hide yes)
			(effects
				(font
					(size 1 1)
					(thickness 0.15)
				)
			)
		)
		(property "Manufacturer" ""
			(at 255.81 230.47 0)
			(layer "F.Fab")
			(hide yes)
			(effects
				(font
					(size 1 1)
					(thickness 0.15)
				)
			)
		)
		(sheetname "M.2")
		(sheetfile "m-2.kicad_sch")
		(attr exclude_from_pos_files exclude_from_bom)
		(fp_circle
			(center 0 0)
			(end 0.475 0)
			(stroke
				(width 0.05)
				(type default)
			)
			(fill none)
			(layer "F.CrtYd")
		)
		(fp_text user "Author: Antmicro"
			(at -0.4 3.901 180)
			(layer "F.Fab")
			(hide yes)
			(effects
				(font
					(size 0.7 0.7)
					(thickness 0.15)
				)
				(justify left bottom)
			)
		)
		(fp_text user "${REFERENCE}"
			(at -0.4 2.7 180)
			(layer "F.Fab")
			(hide yes)
			(effects
				(font
					(size 0.7 0.7)
					(thickness 0.15)
				)
				(justify left bottom)
			)
		)
		(fp_text user "License: Apache-2.0"
			(at -0.4 5.101 180)
			(layer "F.Fab")
			(hide yes)
			(effects
				(font
					(size 0.7 0.7)
					(thickness 0.15)
				)
				(justify left bottom)
			)
		)
		(pad "1" smd circle
			(at 0 0 180)
			(size 0.75 0.75)
			(layers "F.Cu" "F.Mask")
			(net 225 "/M.2/~{M2_E_ALERT}")
			(pinfunction "1")
			(pintype "passive")
		)
	)
	(footprint "antmicro-footprints:R_0402_1005Metric"
		(layer "F.Cu")
		(at 107.3 102.65 -90)
		(descr "Resistor SMD 0402")
		(tags "resistor SMD 0402")
		(property "Reference" "R119"
			(at -0.725 -0.45 -90)
			(layer "F.SilkS")
			(effects
				(font
					(size 0.7 0.7)
					(thickness 0.15)
				)
				(justify left bottom)
			)
		)
		(property "Value" "R_0R_0402"
			(at 0 1.4 -90)
			(layer "F.Fab")
			(effects
				(font
					(size 0.7 0.7)
					(thickness 0.15)
				)
				(justify left bottom)
			)
		)
		(property "Footprint" "antmicro-footprints:R_0402_1005Metric"
			(at 0 0 -90)
			(layer "F.Fab")
			(hide yes)
			(effects
				(font
					(size 1.27 1.27)
					(thickness 0.15)
				)
			)
		)
		(property "Datasheet" "https://industrial.panasonic.com/cdbs/www-data/pdf/RDA0000/AOA0000C301.pdf"
			(at 0 0 -90)
			(layer "F.Fab")
			(hide yes)
			(effects
				(font
					(size 1.27 1.27)
					(thickness 0.15)
				)
			)
		)
		(property "Author" "Antmicro"
			(at 4.65 209.95 0)
			(layer "F.Fab")
			(hide yes)
			(effects
				(font
					(size 1 1)
					(thickness 0.15)
				)
			)
		)
		(property "Current" "1A"
			(at 4.65 209.95 0)
			(layer "F.Fab")
			(hide yes)
			(effects
				(font
					(size 1 1)
					(thickness 0.15)
				)
			)
		)
		(property "License" "Apache-2.0"
			(at 4.65 209.95 0)
			(layer "F.Fab")
			(hide yes)
			(effects
				(font
					(size 1 1)
					(thickness 0.15)
				)
			)
		)
		(property "MPN" "ERJ2GE0R00X"
			(at 4.65 209.95 0)
			(layer "F.Fab")
			(hide yes)
			(effects
				(font
					(size 1 1)
					(thickness 0.15)
				)
			)
		)
		(property "Manufacturer" "Panasonic"
			(at 4.65 209.95 0)
			(layer "F.Fab")
			(hide yes)
			(effects
				(font
					(size 1 1)
					(thickness 0.15)
				)
			)
		)
		(property "Tolerance" ""
			(at 4.65 209.95 0)
			(layer "F.Fab")
			(hide yes)
			(effects
				(font
					(size 1 1)
					(thickness 0.15)
				)
			)
		)
		(property "Val" "0R"
			(at 4.65 209.95 0)
			(layer "F.Fab")
			(hide yes)
			(effects
				(font
					(size 1 1)
					(thickness 0.15)
				)
			)
		)
		(sheetname "USB3")
		(sheetfile "usb3.kicad_sch")
		(attr smd)
		(fp_rect
			(start -0.925 -0.47)
			(end 0.925 0.47)
			(stroke
				(width 0.05)
				(type default)
			)
			(fill none)
			(layer "F.CrtYd")
		)
		(fp_rect
			(start -0.5 -0.25)
			(end 0.5 0.25)
			(stroke
				(width 0.15)
				(type solid)
			)
			(fill none)
			(layer "F.Fab")
		)
		(fp_text user "License: Apache-2.0"
			(at -0.95 5.169 -90)
			(layer "F.Fab")
			(hide yes)
			(effects
				(font
					(size 0.7 0.7)
					(thickness 0.15)
				)
				(justify left bottom)
			)
		)
		(fp_text user "Author: Antmicro"
			(at -0.95 4.169 -90)
			(layer "F.Fab")
			(hide yes)
			(effects
				(font
					(size 0.7 0.7)
					(thickness 0.15)
				)
				(justify left bottom)
			)
		)
		(fp_text user "${REFERENCE}"
			(at -0.95 3.168 -90)
			(layer "F.Fab")
			(hide yes)
			(effects
				(font
					(size 0.7 0.7)
					(thickness 0.15)
				)
				(justify left bottom)
			)
		)
		(pad "1" smd roundrect
			(at -0.48 0 270)
			(size 0.59 0.64)
			(layers "F.Cu" "F.Paste" "F.Mask")
			(roundrect_rratio 0.25)
			(net 1 "GND")
			(pintype "passive")
		)
		(pad "2" smd roundrect
			(at 0.48 0 270)
			(size 0.59 0.64)
			(layers "F.Cu" "F.Paste" "F.Mask")
			(roundrect_rratio 0.25)
			(net 319 "/USB3/~{USBC1_EN_CC}")
			(pintype "passive")
		)
	)
)
